(kicad_pcb
	(version 20241229)
	(generator "pcbnew")
	(generator_version "9.0")
	(general
		(thickness 1.711)
		(legacy_teardrops no)
	)
	(paper "A4")
	(title_block
		(title "Antmicro Baseboard for Jetson AGX Thor")
		(date "2026-02-18")
		(rev "1.1.0")
		(company "Antmicro Ltd")
		(comment 1 "www.antmicro.com")
		(comment 9 "footprints 111-114 of 1170")
	)
	(layers
		(0 "F.Cu" signal)
		(4 "In1.Cu" signal)
		(6 "In2.Cu" signal)
		(8 "In3.Cu" signal)
		(10 "In4.Cu" jumper)
		(12 "In5.Cu" signal)
		(14 "In6.Cu" signal)
		(16 "In7.Cu" signal)
		(18 "In8.Cu" signal)
		(2 "B.Cu" signal)
		(9 "F.Adhes" user "F.Adhesive")
		(11 "B.Adhes" user "B.Adhesive")
		(13 "F.Paste" user)
		(15 "B.Paste" user)
		(5 "F.SilkS" user "F.Silkscreen")
		(7 "B.SilkS" user "B.Silkscreen")
		(1 "F.Mask" user)
		(3 "B.Mask" user)
		(17 "Dwgs.User" user "User.Drawings")
		(19 "Cmts.User" user "User.Comments")
		(21 "Eco1.User" user "User.Eco1")
		(23 "Eco2.User" user "User.Eco2")
		(25 "Edge.Cuts" user)
		(27 "Margin" user)
		(31 "F.CrtYd" user "F.Courtyard")
		(29 "B.CrtYd" user "B.Courtyard")
		(35 "F.Fab" user)
		(33 "B.Fab" user)
	)
	(footprint "antmicro-footprints:R_0402_1005Metric"
		(layer "F.Cu")
		(at 214 130.8 180)
		(descr "Resistor SMD 0402")
		(tags "resistor SMD 0402")
		(property "Reference" "R92"
			(at -1.6 2.3 0)
			(layer "F.SilkS")
			(effects
				(font
					(size 0.7 0.7)
					(thickness 0.15)
				)
				(justify right top)
			)
		)
		(property "Value" "R_49k9_0402"
			(at -1.011843 1.772047 0)
			(layer "F.Fab")
			(effects
				(font
					(size 0.7 0.7)
					(thickness 0.15)
				)
				(justify right top)
			)
		)
		(property "Datasheet" "https://www.bourns.com/docs/product-datasheets/cr.pdf"
			(at 0 0 0)
			(layer "F.Fab")
			(hide yes)
			(effects
				(font
					(size 1.27 1.27)
					(thickness 0.15)
				)
			)
		)
		(property "Description" "SMD Chip Resistor, 49.9 kohm, ± 1%, 63 mW, 0402 [1005 Metric], Thick Film, General Purpose"
			(at 0 0 0)
			(layer "F.Fab")
			(hide yes)
			(effects
				(font
					(size 1.27 1.27)
					(thickness 0.15)
				)
			)
		)
		(property "MPN" "CR0402-FX-4992GLF"
			(at 0 0 180)
			(unlocked yes)
			(layer "F.Fab")
			(hide yes)
			(effects
				(font
					(size 1 1)
					(thickness 0.15)
				)
			)
		)
		(property "Manufacturer" "Bourns"
			(at 0 0 180)
			(unlocked yes)
			(layer "F.Fab")
			(hide yes)
			(effects
				(font
					(size 1 1)
					(thickness 0.15)
				)
			)
		)
		(property "License" "Apache-2.0"
			(at 0 0 180)
			(unlocked yes)
			(layer "F.Fab")
			(hide yes)
			(effects
				(font
					(size 1 1)
					(thickness 0.15)
				)
			)
		)
		(property "Author" "Antmicro"
			(at 0 0 180)
			(unlocked yes)
			(layer "F.Fab")
			(hide yes)
			(effects
				(font
					(size 1 1)
					(thickness 0.15)
				)
			)
		)
		(property "Val" "49k9"
			(at 0 0 180)
			(unlocked yes)
			(layer "F.Fab")
			(hide yes)
			(effects
				(font
					(size 1 1)
					(thickness 0.15)
				)
			)
		)
		(property "Tolerance" "1%"
			(at 0 0 180)
			(unlocked yes)
			(layer "F.Fab")
			(hide yes)
			(effects
				(font
					(size 1 1)
					(thickness 0.15)
				)
			)
		)
		(sheetname "/USB Hub/")
		(sheetfile "usb_hub.kicad_sch")
		(attr smd)
		(fp_rect
			(start -0.925 -0.47)
			(end 0.925 0.47)
			(stroke
				(width 0.05)
				(type default)
			)
			(fill no)
			(layer "F.CrtYd")
		)
		(fp_rect
			(start -0.5 -0.25)
			(end 0.5 0.25)
			(stroke
				(width 0.15)
				(type solid)
			)
			(fill no)
			(layer "F.Fab")
		)
		(fp_text user "${REFERENCE}"
			(at -0.95 3.168 0)
			(layer "F.Fab")
			(effects
				(font
					(size 0.7 0.7)
					(thickness 0.15)
				)
				(justify right top)
			)
		)
		(fp_text user "Author: Antmicro"
			(at -0.95 4.169 0)
			(layer "F.Fab")
			(effects
				(font
					(size 0.7 0.7)
					(thickness 0.15)
				)
				(justify right top)
			)
		)
		(fp_text user "License: Apache-2.0"
			(at -0.95 5.169 0)
			(layer "F.Fab")
			(effects
				(font
					(size 0.7 0.7)
					(thickness 0.15)
				)
				(justify right top)
			)
		)
		(pad "1" smd roundrect
			(at -0.48 0 180)
			(size 0.59 0.64)
			(layers "F.Cu" "F.Mask" "F.Paste")
			(roundrect_rratio 0.25)
			(net 1 "GND")
			(pintype "passive")
		)
		(pad "2" smd roundrect
			(at 0.48 0 180)
			(size 0.59 0.64)
			(layers "F.Cu" "F.Mask" "F.Paste")
			(roundrect_rratio 0.25)
			(net 932 "/USB Hub/USBC4_VBUS_MON")
			(pintype "passive")
		)
	)
	(footprint "antmicro-footprints:LED_0603_1608Metric_G"
		(layer "F.Cu")
		(at 197.55 88.22 90)
		(descr "LED SMD 0603 Green")
		(tags "LED SMD 0603 Green")
		(property "Reference" "D19"
			(at -3.42 0.35 90)
			(layer "F.SilkS")
			(effects
				(font
					(size 0.7 0.7)
					(thickness 0.15)
				)
				(justify left bottom)
			)
		)
		(property "Value" "LED_G_0603_LTST-C190GKT"
			(at -0.001 1.599 90)
			(layer "F.Fab")
			(effects
				(font
					(size 0.7 0.7)
					(thickness 0.15)
				)
				(justify left bottom)
			)
		)
		(property "Datasheet" "https://media.digikey.com/pdf/Data%20Sheets/Lite-On%20PDFs/LTST-C190GKT.pdf"
			(at 0 0 90)
			(layer "F.Fab")
			(hide yes)
			(effects
				(font
					(size 1.27 1.27)
					(thickness 0.15)
				)
			)
		)
		(property "Description" "LED, Green, SMD, 0603, 20 mA, 2.1 V, 569 nm"
			(at 0 0 90)
			(layer "F.Fab")
			(hide yes)
			(effects
				(font
					(size 1.27 1.27)
					(thickness 0.15)
				)
			)
		)
		(property "MPN" "LTST-C190GKT"
			(at 0 0 90)
			(unlocked yes)
			(layer "F.Fab")
			(hide yes)
			(effects
				(font
					(size 1 1)
					(thickness 0.15)
				)
			)
		)
		(property "Manufacturer" "Lite-On"
			(at 0 0 90)
			(unlocked yes)
			(layer "F.Fab")
			(hide yes)
			(effects
				(font
					(size 1 1)
					(thickness 0.15)
				)
			)
		)
		(property "Author" "Antmicro"
			(at 0 0 90)
			(unlocked yes)
			(layer "F.Fab")
			(hide yes)
			(effects
				(font
					(size 1 1)
					(thickness 0.15)
				)
			)
		)
		(property "License" "Apache-2.0"
			(at 0 0 90)
			(unlocked yes)
			(layer "F.Fab")
			(hide yes)
			(effects
				(font
					(size 1 1)
					(thickness 0.15)
				)
			)
		)
		(property "Color" "Green"
			(at 0 0 90)
			(unlocked yes)
			(layer "F.Fab")
			(hide yes)
			(effects
				(font
					(size 1 1)
					(thickness 0.15)
				)
			)
		)
		(sheetname "/USB Debug, PD/")
		(sheetfile "usb_debug_pd.kicad_sch")
		(attr smd)
		(fp_line
			(start 0.22 -0.35)
			(end -0.22 -0.35)
			(stroke
				(width 0.15)
				(type solid)
			)
			(layer "F.SilkS")
		)
		(fp_line
			(start -1.18 -0.319)
			(end -1.18 0.321)
			(stroke
				(width 0.15)
				(type solid)
			)
			(layer "F.SilkS")
		)
		(fp_line
			(start 0.105328 0.001008)
			(end 0.24 0.001)
			(stroke
				(width 0.1)
				(type solid)
			)
			(layer "F.SilkS")
		)
		(fp_line
			(start -0.094672 0.001008)
			(end 0.105328 -0.198992)
			(stroke
				(width 0.1)
				(type solid)
			)
			(layer "F.SilkS")
		)
		(fp_line
			(start -0.094672 0.001008)
			(end -0.24 0.001008)
			(stroke
				(width 0.1)
				(type solid)
			)
			(layer "F.SilkS")
		)
		(fp_line
			(start 0.105328 0.201008)
			(end 0.105328 -0.198992)
			(stroke
				(width 0.1)
				(type solid)
			)
			(layer "F.SilkS")
		)
		(fp_line
			(start 0.105328 0.201008)
			(end -0.094672 0.001008)
			(stroke
				(width 0.1)
				(type solid)
			)
			(layer "F.SilkS")
		)
		(fp_line
			(start -0.094672 0.201008)
			(end -0.094672 -0.198992)
			(stroke
				(width 0.1)
				(type solid)
			)
			(layer "F.SilkS")
		)
		(fp_line
			(start 0.22 0.35)
			(end -0.22 0.35)
			(stroke
				(width 0.15)
				(type solid)
			)
			(layer "F.SilkS")
		)
		(fp_rect
			(start 1.25 0.65)
			(end -1.25 -0.65)
			(stroke
				(width 0.05)
				(type solid)
			)
			(fill no)
			(layer "F.CrtYd")
		)
		(fp_line
			(start 0.201 -0.202)
			(end -0.101 0)
			(stroke
				(width 0.15)
				(type solid)
			)
			(layer "F.Fab")
		)
		(fp_line
			(start -0.199 -0.202)
			(end -0.199 0.1)
			(stroke
				(width 0.15)
				(type solid)
			)
			(layer "F.Fab")
		)
		(fp_line
			(start 0.599 0)
			(end 0.201 0)
			(stroke
				(width 0.15)
				(type solid)
			)
			(layer "F.Fab")
		)
		(fp_line
			(start 0.201 0)
			(end 0.201 -0.202)
			(stroke
				(width 0.15)
				(type solid)
			)
			(layer "F.Fab")
		)
		(fp_line
			(start -0.101 0)
			(end 0.201 0.2)
			(stroke
				(width 0.15)
				(type solid)
			)
			(layer "F.Fab")
		)
		(fp_line
			(start -0.199 0)
			(end -0.597 0)
			(stroke
				(width 0.15)
				(type solid)
			)
			(layer "F.Fab")
		)
		(fp_line
			(start 0.201 0.2)
			(end 0.201 0)
			(stroke
				(width 0.15)
				(type solid)
			)
			(layer "F.Fab")
		)
		(fp_line
			(start -0.199 0.2)
			(end -0.199 0.1)
			(stroke
				(width 0.15)
				(type solid)
			)
			(layer "F.Fab")
		)
		(fp_rect
			(start 0.848 0.4)
			(end -0.85 -0.402)
			(stroke
				(width 0.15)
				(type solid)
			)
			(fill no)
			(layer "F.Fab")
		)
		(fp_text user "License: Apache-2.0"
			(at -1.4224 3.599 90)
			(layer "F.Fab")
			(effects
				(font
					(size 0.7 0.7)
					(thickness 0.15)
				)
				(justify left bottom)
			)
		)
		(fp_text user "${REFERENCE}"
			(at -1.4224 5.999 90)
			(layer "F.Fab")
			(effects
				(font
					(size 0.7 0.7)
					(thickness 0.15)
				)
				(justify left bottom)
			)
		)
		(fp_text user "Author: Antmicro"
			(at -1.4224 4.799 90)
			(layer "F.Fab")
			(effects
				(font
					(size 0.7 0.7)
					(thickness 0.15)
				)
				(justify left bottom)
			)
		)
		(pad "1" smd roundrect
			(at -0.7 0 270)
			(size 0.8 1)
			(layers "F.Cu" "F.Mask" "F.Paste")
			(roundrect_rratio 0.2)
			(net 1 "GND")
			(pinfunction "C")
			(pintype "passive")
		)
		(pad "2" smd roundrect
			(at 0.7 0 270)
			(size 0.8 1)
			(layers "F.Cu" "F.Mask" "F.Paste")
			(roundrect_rratio 0.2)
			(net 534 "Net-(D19-A)")
			(pinfunction "A")
			(pintype "passive")
		)
	)
	(footprint "antmicro-footprints:R_0402_1005Metric"
		(layer "F.Cu")
		(at 67.500532 55.769 90)
		(descr "Resistor SMD 0402")
		(tags "resistor SMD 0402")
		(property "Reference" "R306"
			(at -1.281 -1.700532 90)
			(layer "F.SilkS")
			(effects
				(font
					(size 0.7 0.7)
					(thickness 0.15)
				)
				(justify left bottom)
			)
		)
		(property "Value" "R_470R_0402"
			(at -1.011843 1.772046 90)
			(layer "F.Fab")
			(effects
				(font
					(size 0.7 0.7)
					(thickness 0.15)
				)
				(justify left bottom)
			)
		)
		(property "Datasheet" "https://www.bourns.com/docs/product-datasheets/cr.pdf"
			(at 0 0 90)
			(layer "F.Fab")
			(hide yes)
			(effects
				(font
					(size 1.27 1.27)
					(thickness 0.15)
				)
			)
		)
		(property "Description" "SMD Chip Resistor, 470 ohm, ± 1%, 62.5 mW, 0402 [1005 Metric], Thick Film, General Purpose"
			(at 0 0 90)
			(layer "F.Fab")
			(hide yes)
			(effects
				(font
					(size 1.27 1.27)
					(thickness 0.15)
				)
			)
		)
		(property "MPN" "CR0402-FX-4700GLF"
			(at 0 0 90)
			(unlocked yes)
			(layer "F.Fab")
			(hide yes)
			(effects
				(font
					(size 1 1)
					(thickness 0.15)
				)
			)
		)
		(property "Manufacturer" "Bourns"
			(at 0 0 90)
			(unlocked yes)
			(layer "F.Fab")
			(hide yes)
			(effects
				(font
					(size 1 1)
					(thickness 0.15)
				)
			)
		)
		(property "License" "Apache-2.0"
			(at 0 0 90)
			(unlocked yes)
			(layer "F.Fab")
			(hide yes)
			(effects
				(font
					(size 1 1)
					(thickness 0.15)
				)
			)
		)
		(property "Author" "Antmicro"
			(at 0 0 90)
			(unlocked yes)
			(layer "F.Fab")
			(hide yes)
			(effects
				(font
					(size 1 1)
					(thickness 0.15)
				)
			)
		)
		(property "Val" "470R"
			(at 0 0 90)
			(unlocked yes)
			(layer "F.Fab")
			(hide yes)
			(effects
				(font
					(size 1 1)
					(thickness 0.15)
				)
			)
		)
		(property "Tolerance" "1%"
			(at 0 0 90)
			(unlocked yes)
			(layer "F.Fab")
			(hide yes)
			(effects
				(font
					(size 1 1)
					(thickness 0.15)
				)
			)
		)
		(sheetname "/SoM_Power/")
		(sheetfile "som_power.kicad_sch")
		(attr smd)
		(fp_poly
			(pts
				(xy -0.925 -0.47) (xy -0.925 0.47) (xy 0.925 0.47) (xy 0.925 -0.47)
			)
			(stroke
				(width 0.05)
				(type default)
			)
			(fill no)
			(layer "F.CrtYd")
		)
		(fp_poly
			(pts
				(xy -0.5 -0.25) (xy -0.5 0.25) (xy 0.5 0.25) (xy 0.5 -0.25)
			)
			(stroke
				(width 0.15)
				(type solid)
			)
			(fill no)
			(layer "F.Fab")
		)
		(fp_text user "License: Apache-2.0"
			(at -0.949999 5.169 90)
			(layer "F.Fab")
			(effects
				(font
					(size 0.7 0.7)
					(thickness 0.15)
				)
				(justify left bottom)
			)
		)
		(fp_text user "Author: Antmicro"
			(at -0.95 4.169 90)
			(layer "F.Fab")
			(effects
				(font
					(size 0.7 0.7)
					(thickness 0.15)
				)
				(justify left bottom)
			)
		)
		(fp_text user "${REFERENCE}"
			(at -0.95 3.168 90)
			(layer "F.Fab")
			(effects
				(font
					(size 0.7 0.7)
					(thickness 0.15)
				)
				(justify left bottom)
			)
		)
		(pad "1" smd roundrect
			(at -0.48 0 90)
			(size 0.59 0.64)
			(layers "F.Cu" "F.Mask" "F.Paste")
			(roundrect_rratio 0.25)
			(net 549 "Net-(D52-A)")
			(pintype "passive")
		)
		(pad "2" smd roundrect
			(at 0.48 0 90)
			(size 0.59 0.64)
			(layers "F.Cu" "F.Mask" "F.Paste")
			(roundrect_rratio 0.25)
			(net 491 "+5V_AON")
			(pintype "passive")
		)
	)
	(footprint "antmicro-footprints:C_0805_2012Metric"
		(layer "F.Cu")
		(at 173.17 93.32 -90)
		(descr "Capacitor SMD 0805")
		(tags "capacitor SMD 0805")
		(property "Reference" "C298"
			(at 1.745 0.425 90)
			(layer "F.SilkS")
			(effects
				(font
					(size 0.7 0.7)
					(thickness 0.15)
				)
				(justify right top)
			)
		)
		(property "Value" "C_22u_25V_0805"
			(at -2.055717 1.963152 90)
			(layer "F.Fab")
			(effects
				(font
					(size 0.7 0.7)
					(thickness 0.15)
				)
				(justify right top)
			)
		)
		(property "Datasheet" "https://product.samsungsem.com/mlcc/CL21A226MAYNNN.do"
			(at 0 0 90)
			(layer "F.Fab")
			(hide yes)
			(effects
				(font
					(size 1.27 1.27)
					(thickness 0.15)
				)
			)
		)
		(property "Description" "SMT Multilayer Ceramic Capacitor, 22uF, +/-20%, 25V, X5R, 0805 [2012 Metric]"
			(at 0 0 90)
			(layer "F.Fab")
			(hide yes)
			(effects
				(font
					(size 1.27 1.27)
					(thickness 0.15)
				)
			)
		)
		(property "MPN" "CL21A226MAYNNNE"
			(at 0 0 270)
			(unlocked yes)
			(layer "F.Fab")
			(hide yes)
			(effects
				(font
					(size 1 1)
					(thickness 0.15)
				)
			)
		)
		(property "Manufacturer" "Samsung Electro-Mechanics"
			(at 0 0 270)
			(unlocked yes)
			(layer "F.Fab")
			(hide yes)
			(effects
				(font
					(size 1 1)
					(thickness 0.15)
				)
			)
		)
		(property "License" "Apache-2.0"
			(at 0 0 270)
			(unlocked yes)
			(layer "F.Fab")
			(hide yes)
			(effects
				(font
					(size 1 1)
					(thickness 0.15)
				)
			)
		)
		(property "Author" "Antmicro"
			(at 0 0 270)
			(unlocked yes)
			(layer "F.Fab")
			(hide yes)
			(effects
				(font
					(size 1 1)
					(thickness 0.15)
				)
			)
		)
		(property "Val" "22u"
			(at 0 0 270)
			(unlocked yes)
			(layer "F.Fab")
			(hide yes)
			(effects
				(font
					(size 1 1)
					(thickness 0.15)
				)
			)
		)
		(property "Voltage" "25V"
			(at 0 0 270)
			(unlocked yes)
			(layer "F.Fab")
			(hide yes)
			(effects
				(font
					(size 1 1)
					(thickness 0.15)
				)
			)
		)
		(property "Dielectric" "X5R"
			(at 0 0 270)
			(unlocked yes)
			(layer "F.Fab")
			(hide yes)
			(effects
				(font
					(size 1 1)
					(thickness 0.15)
				)
			)
		)
		(property "Public" "False"
			(at 0 0 270)
			(unlocked yes)
			(layer "F.Fab")
			(hide yes)
			(effects
				(font
					(size 1 1)
					(thickness 0.15)
				)
			)
		)
		(component_classes
			(class "DCDC_SOM")
		)
		(sheetname "/DCDC/")
		(sheetfile "dcdc.kicad_sch")
		(attr smd)
		(fp_line
			(start -0.3 0.7)
			(end 0.3 0.7)
			(stroke
				(width 0.15)
				(type solid)
			)
			(layer "F.SilkS")
		)
		(fp_line
			(start -0.3 -0.7)
			(end 0.3 -0.7)
			(stroke
				(width 0.15)
				(type solid)
			)
			(layer "F.SilkS")
		)
		(fp_rect
			(start 1.95 -0.9)
			(end -1.95 0.9)
			(stroke
				(width 0.05)
				(type default)
			)
			(fill no)
			(layer "F.CrtYd")
		)
		(fp_rect
			(start -0.95 -0.675)
			(end 0.95 0.675)
			(stroke
				(width 0.15)
				(type solid)
			)
			(fill no)
			(layer "F.Fab")
		)
		(fp_text user "License: Apache-2.0"
			(at -1.9 4.947 90)
			(layer "F.Fab")
			(effects
				(font
					(size 0.7 0.7)
					(thickness 0.15)
				)
				(justify right top)
			)
		)
		(fp_text user "${REFERENCE}"
			(at -1.9 3.947 90)
			(layer "F.Fab")
			(effects
				(font
					(size 0.7 0.7)
					(thickness 0.15)
				)
				(justify right top)
			)
		)
		(fp_text user "Author: Antmicro"
			(at -1.9 5.947 90)
			(layer "F.Fab")
			(effects
				(font
					(size 0.7 0.7)
					(thickness 0.15)
				)
				(justify right top)
			)
		)
		(pad "1" smd roundrect
			(at -1.1 0 270)
			(size 1.2 1.3)
			(layers "F.Cu" "F.Mask" "F.Paste")
			(roundrect_rratio 0.25)
			(net 1 "GND")
			(pintype "passive")
		)
		(pad "2" smd roundrect
			(at 1.1 0 270)
			(size 1.2 1.3)
			(layers "F.Cu" "F.Mask" "F.Paste")
			(roundrect_rratio 0.25)
			(net 903 "/DCDC/16V_OUT")
			(pintype "passive")
		)
	)
)
